(kicad_pcb
	(version 20260206)
	(generator "pcbnew")
	(generator_version "10.0")
	(general
		(thickness 1.6)
		(legacy_teardrops no)
	)
	(paper "A4")
	(title_block
		(title "pdpb — Lightning_PDPB_BRD.brd")
		(comment 1 "Lightning (Wiwynn / Facebook NVMe JBOF) / footprints 643-649 of 1140")
	)
	(layers
		(0 "F.Cu" signal "TOP")
		(4 "In1.Cu" signal "L2GND")
		(6 "In2.Cu" signal "L3")
		(8 "In3.Cu" signal "L4VCC")
		(10 "In4.Cu" signal "L5VCC")
		(12 "In5.Cu" signal "L6")
		(14 "In6.Cu" signal "L7GND")
		(2 "B.Cu" signal "BOTTOM")
		(9 "F.Adhes" user "F.Adhesive")
		(11 "B.Adhes" user "B.Adhesive")
		(13 "F.Paste" user "Package Geometry/Pastemask Top")
		(15 "B.Paste" user "Package Geometry/Pastemask Bottom")
		(5 "F.SilkS" user "Ref Des/Silkscreen Top")
		(7 "B.SilkS" user "Ref Des/Silkscreen Bottom")
		(1 "F.Mask" user "Board Geometry/Soldermask Top")
		(3 "B.Mask" user "Board Geometry/Soldermask Bottom")
		(17 "Dwgs.User" user "User.Drawings")
		(19 "Cmts.User" user "User.Comments")
		(21 "Eco1.User" user "User.Eco1")
		(23 "Eco2.User" user "User.Eco2")
		(25 "Edge.Cuts" user "Board Geometry/Outline")
		(27 "Margin" user)
		(31 "F.CrtYd" user "Package Geometry/Place Bound Top")
		(29 "B.CrtYd" user "Package Geometry/Place Bound Bottom")
		(35 "F.Fab" user "Ref Des/Assembly Top")
		(33 "B.Fab" user "Ref Des/Assembly Bottom")
	)
	(footprint ""
		(layer "F.Cu")
		(at 234.061 -239.008158 90)
		(property "Reference" "R9795"
			(at 0 0 90)
			(layer "F.SilkS")
			(hide yes)
			(effects
				(font
					(size 1.27 1.27)
				)
			)
		)
		(property "Value" "0R2J-2-GP"
			(at 0.064008 -3.993896 90)
			(unlocked yes)
			(layer "F.Fab")
			(hide yes)
			(effects
				(font
					(size 1.016 1.016)
					(thickness 0.1524)
				)
			)
		)
		(property "Device Type" "R402H16"
			(at 0.064008 -5.517896 90)
			(unlocked yes)
			(layer "F.Fab")
			(hide yes)
			(effects
				(font
					(size 1.016 1.016)
					(thickness 0.1524)
				)
			)
		)
		(duplicate_pad_numbers_are_jumpers no)
		(fp_line
			(start 0.508 -0.9398)
			(end -0.508 -0.9398)
			(stroke
				(width 0.1524)
				(type default)
			)
			(layer "F.SilkS")
		)
		(fp_line
			(start -0.508 -0.9398)
			(end -0.508 0.9398)
			(stroke
				(width 0.1524)
				(type default)
			)
			(layer "F.SilkS")
		)
		(fp_rect
			(start -0.508 0.9398)
			(end 0.508 -0.9398)
			(stroke
				(width 0)
				(type default)
			)
			(fill no)
			(layer "F.CrtYd")
		)
		(fp_rect
			(start -0.508 0.9398)
			(end 0.508 -0.9398)
			(stroke
				(width 0)
				(type default)
			)
			(fill no)
			(layer "F.Fab")
		)
		(pad "1" smd custom
			(at 0 -0.4445 90)
			(size 0.1397 0.1397)
			(layers "F.Cu" "F.Mask" "F.Paste")
			(net "ATTN_LED_DR2_AND")
			(options
				(clearance outline)
				(anchor circle)
			)
			(primitives
				(gr_poly
					(pts
						(arc
							(start -0.1778 -0.2794)
							(mid -0.249642 -0.249642)
							(end -0.2794 -0.1778)
						)
						(arc
							(start -0.2794 0.1778)
							(mid -0.249642 0.249642)
							(end -0.1778 0.2794)
						)
						(arc
							(start 0.1778 0.2794)
							(mid 0.249642 0.249642)
							(end 0.2794 0.1778)
						)
						(arc
							(start 0.2794 -0.1778)
							(mid 0.249642 -0.249642)
							(end 0.1778 -0.2794)
						)
					)
					(width 0)
					(fill yes)
				)
			)
		)
		(pad "2" smd custom
			(at 0 0.4445 90)
			(size 0.1397 0.1397)
			(layers "F.Cu" "F.Mask" "F.Paste")
			(net "ATTN_LED_DR2_AND_R")
			(options
				(clearance outline)
				(anchor circle)
			)
			(primitives
				(gr_poly
					(pts
						(arc
							(start -0.1778 -0.2794)
							(mid -0.249642 -0.249642)
							(end -0.2794 -0.1778)
						)
						(arc
							(start -0.2794 0.1778)
							(mid -0.249642 0.249642)
							(end -0.1778 0.2794)
						)
						(arc
							(start 0.1778 0.2794)
							(mid 0.249642 0.249642)
							(end 0.2794 0.1778)
						)
						(arc
							(start 0.2794 -0.1778)
							(mid 0.249642 -0.249642)
							(end 0.1778 -0.2794)
						)
					)
					(width 0)
					(fill yes)
				)
			)
		)
	)
	(footprint ""
		(layer "F.Cu")
		(at 96.266 -439.674)
		(property "Reference" "R9511"
			(at 0 0 0)
			(layer "F.SilkS")
			(hide yes)
			(effects
				(font
					(size 1.27 1.27)
				)
			)
		)
		(property "Value" "4K7R2F-GP"
			(at 0.064008 -3.993896 0)
			(unlocked yes)
			(layer "F.Fab")
			(hide yes)
			(effects
				(font
					(size 1.016 1.016)
					(thickness 0.1524)
				)
			)
		)
		(property "Device Type" "R402H16"
			(at 0.064008 -5.517896 0)
			(unlocked yes)
			(layer "F.Fab")
			(hide yes)
			(effects
				(font
					(size 1.016 1.016)
					(thickness 0.1524)
				)
			)
		)
		(duplicate_pad_numbers_are_jumpers no)
		(fp_line
			(start -0.508 -0.9398)
			(end -0.508 0.9398)
			(stroke
				(width 0.1524)
				(type default)
			)
			(layer "F.SilkS")
		)
		(fp_line
			(start 0.508 -0.9398)
			(end -0.508 -0.9398)
			(stroke
				(width 0.1524)
				(type default)
			)
			(layer "F.SilkS")
		)
		(fp_rect
			(start -0.508 0.9398)
			(end 0.508 -0.9398)
			(stroke
				(width 0)
				(type default)
			)
			(fill no)
			(layer "F.CrtYd")
		)
		(fp_rect
			(start -0.508 0.9398)
			(end 0.508 -0.9398)
			(stroke
				(width 0)
				(type default)
			)
			(fill no)
			(layer "F.Fab")
		)
		(pad "1" smd custom
			(at 0 -0.4445)
			(size 0.1397 0.1397)
			(layers "F.Cu" "F.Mask" "F.Paste")
			(net "P3V3")
			(options
				(clearance outline)
				(anchor circle)
			)
			(primitives
				(gr_poly
					(pts
						(arc
							(start -0.1778 -0.2794)
							(mid -0.249642 -0.249642)
							(end -0.2794 -0.1778)
						)
						(arc
							(start -0.2794 0.1778)
							(mid -0.249642 0.249642)
							(end -0.1778 0.2794)
						)
						(arc
							(start 0.1778 0.2794)
							(mid 0.249642 0.249642)
							(end 0.2794 0.1778)
						)
						(arc
							(start 0.2794 -0.1778)
							(mid 0.249642 -0.249642)
							(end 0.1778 -0.2794)
						)
					)
					(width 0)
					(fill yes)
				)
			)
		)
		(pad "2" smd custom
			(at 0 0.4445)
			(size 0.1397 0.1397)
			(layers "F.Cu" "F.Mask" "F.Paste")
			(net "CLK_BUFFER_EU1_VOE_N")
			(options
				(clearance outline)
				(anchor circle)
			)
			(primitives
				(gr_poly
					(pts
						(arc
							(start -0.1778 -0.2794)
							(mid -0.249642 -0.249642)
							(end -0.2794 -0.1778)
						)
						(arc
							(start -0.2794 0.1778)
							(mid -0.249642 0.249642)
							(end -0.1778 0.2794)
						)
						(arc
							(start 0.1778 0.2794)
							(mid 0.249642 0.249642)
							(end 0.2794 0.1778)
						)
						(arc
							(start 0.2794 -0.1778)
							(mid 0.249642 -0.249642)
							(end 0.1778 -0.2794)
						)
					)
					(width 0)
					(fill yes)
				)
			)
		)
	)
	(footprint ""
		(layer "F.Cu")
		(at 43.50004 -41.099994)
		(property "Reference" "LED9"
			(at 0 0 0)
			(layer "F.SilkS")
			(hide yes)
			(effects
				(font
					(size 1.27 1.27)
				)
			)
		)
		(property "Value" "LED-RB-4-GP"
			(at 5.88899 1.80848 0)
			(unlocked yes)
			(layer "F.Fab")
			(hide yes)
			(effects
				(font
					(size 1.016 1.016)
					(thickness 0.1524)
				)
			)
		)
		(property "Device Type" "LED1613-4PH20"
			(at 5.88899 0.28448 0)
			(unlocked yes)
			(layer "F.Fab")
			(hide yes)
			(effects
				(font
					(size 1.016 1.016)
					(thickness 0.1524)
				)
			)
		)
		(duplicate_pad_numbers_are_jumpers no)
		(fp_line
			(start -1.4478 -0.9652)
			(end 1.4478 -0.9652)
			(stroke
				(width 0.1524)
				(type default)
			)
			(layer "F.SilkS")
		)
		(fp_line
			(start -1.4478 0.9652)
			(end -1.4478 -0.9652)
			(stroke
				(width 0.1524)
				(type default)
			)
			(layer "F.SilkS")
		)
		(fp_line
			(start -1.4478 0.9652)
			(end -1.4478 -0.9652)
			(stroke
				(width 0.508)
				(type default)
			)
			(layer "F.SilkS")
		)
		(fp_line
			(start 1.4478 -0.9652)
			(end 1.4478 0.9652)
			(stroke
				(width 0.1524)
				(type default)
			)
			(layer "F.SilkS")
		)
		(fp_line
			(start 1.4478 0.9652)
			(end -1.4478 0.9652)
			(stroke
				(width 0.1524)
				(type default)
			)
			(layer "F.SilkS")
		)
		(fp_rect
			(start -0.8001 0.6477)
			(end 0.8001 -0.6477)
			(stroke
				(width 0)
				(type default)
			)
			(fill no)
			(layer "F.CrtYd")
		)
		(fp_poly
			(pts
				(xy -1.7018 1.2192) (xy -1.7018 -0.06223) (xy -0.8001 -0.06223) (xy -0.8001 0.6477) (xy 0.8001 0.6477)
				(xy 0.8001 -0.6477) (xy -0.8001 -0.6477) (xy -0.8001 -0.0635) (xy -1.7018 -0.0635) (xy -1.7018 -1.2192)
				(xy 1.7018 -1.2192) (xy 1.7018 1.2192)
			)
			(stroke
				(width 0)
				(type default)
			)
			(fill no)
			(layer "F.CrtYd")
		)
		(fp_rect
			(start -1.7018 1.2192)
			(end 1.7018 -1.2192)
			(stroke
				(width 0)
				(type default)
			)
			(fill no)
			(layer "F.Fab")
		)
		(pad "1" smd rect
			(at -0.73025 0.4064)
			(size 0.9144 0.6096)
			(layers "F.Cu" "F.Mask" "F.Paste")
			(net "SSD_ACT_DR9_MOS_N")
		)
		(pad "2" smd rect
			(at -0.73025 -0.4064)
			(size 0.9144 0.6096)
			(layers "F.Cu" "F.Mask" "F.Paste")
			(net "ATTN_LED_DR9_MOS_N")
		)
		(pad "3" smd rect
			(at 0.73025 -0.4064)
			(size 0.9144 0.6096)
			(layers "F.Cu" "F.Mask" "F.Paste")
			(net "DRV_ATTN_9")
		)
		(pad "4" smd rect
			(at 0.73025 0.4064)
			(size 0.9144 0.6096)
			(layers "F.Cu" "F.Mask" "F.Paste")
			(net "DRV_ACT_9")
		)
	)
	(footprint ""
		(layer "F.Cu")
		(at 89.662 -418.338 180)
		(property "Reference" "R9609"
			(at 0 0 180)
			(layer "F.SilkS")
			(hide yes)
			(effects
				(font
					(size 1.27 1.27)
				)
			)
		)
		(property "Value" "10R2F-L-GP"
			(at 0.064008 -3.993896 180)
			(unlocked yes)
			(layer "F.Fab")
			(hide yes)
			(effects
				(font
					(size 1.016 1.016)
					(thickness 0.1524)
				)
			)
		)
		(property "Device Type" "R402H14"
			(at 0.064008 -5.517896 180)
			(unlocked yes)
			(layer "F.Fab")
			(hide yes)
			(effects
				(font
					(size 1.016 1.016)
					(thickness 0.1524)
				)
			)
		)
		(duplicate_pad_numbers_are_jumpers no)
		(fp_line
			(start 0.508 -0.9398)
			(end -0.508 -0.9398)
			(stroke
				(width 0.1524)
				(type default)
			)
			(layer "F.SilkS")
		)
		(fp_line
			(start -0.508 -0.9398)
			(end -0.508 0.9398)
			(stroke
				(width 0.1524)
				(type default)
			)
			(layer "F.SilkS")
		)
		(fp_rect
			(start -0.508 0.9398)
			(end 0.508 -0.9398)
			(stroke
				(width 0)
				(type default)
			)
			(fill no)
			(layer "F.CrtYd")
		)
		(fp_rect
			(start -0.508 0.9398)
			(end 0.508 -0.9398)
			(stroke
				(width 0)
				(type default)
			)
			(fill no)
			(layer "F.Fab")
		)
		(pad "1" smd custom
			(at 0 -0.4445 180)
			(size 0.1397 0.1397)
			(layers "F.Cu" "F.Mask" "F.Paste")
			(net "SSD10_CLK0_OE_N")
			(options
				(clearance outline)
				(anchor circle)
			)
			(primitives
				(gr_poly
					(pts
						(arc
							(start -0.1778 -0.2794)
							(mid -0.249642 -0.249642)
							(end -0.2794 -0.1778)
						)
						(arc
							(start -0.2794 0.1778)
							(mid -0.249642 0.249642)
							(end -0.1778 0.2794)
						)
						(arc
							(start 0.1778 0.2794)
							(mid 0.249642 0.249642)
							(end 0.2794 0.1778)
						)
						(arc
							(start 0.2794 -0.1778)
							(mid 0.249642 -0.249642)
							(end 0.1778 -0.2794)
						)
					)
					(width 0)
					(fill yes)
				)
			)
		)
		(pad "2" smd custom
			(at 0 0.4445 180)
			(size 0.1397 0.1397)
			(layers "F.Cu" "F.Mask" "F.Paste")
			(net "SSD10_CLK0_OE_R_N")
			(options
				(clearance outline)
				(anchor circle)
			)
			(primitives
				(gr_poly
					(pts
						(arc
							(start -0.1778 -0.2794)
							(mid -0.249642 -0.249642)
							(end -0.2794 -0.1778)
						)
						(arc
							(start -0.2794 0.1778)
							(mid -0.249642 0.249642)
							(end -0.1778 0.2794)
						)
						(arc
							(start 0.1778 0.2794)
							(mid 0.249642 0.249642)
							(end 0.2794 0.1778)
						)
						(arc
							(start 0.2794 -0.1778)
							(mid 0.249642 -0.249642)
							(end 0.1778 -0.2794)
						)
					)
					(width 0)
					(fill yes)
				)
			)
		)
	)
	(footprint ""
		(layer "F.Cu")
		(at 229.235 -439.166)
		(property "Reference" "R9234"
			(at 0 0 0)
			(layer "F.SilkS")
			(hide yes)
			(effects
				(font
					(size 1.27 1.27)
				)
			)
		)
		(property "Value" "0R2J-2-GP"
			(at 0.064008 -3.993896 0)
			(unlocked yes)
			(layer "F.Fab")
			(hide yes)
			(effects
				(font
					(size 1.016 1.016)
					(thickness 0.1524)
				)
			)
		)
		(property "Device Type" "R402H16"
			(at 0.064008 -5.517896 0)
			(unlocked yes)
			(layer "F.Fab")
			(hide yes)
			(effects
				(font
					(size 1.016 1.016)
					(thickness 0.1524)
				)
			)
		)
		(duplicate_pad_numbers_are_jumpers no)
		(fp_line
			(start -0.508 -0.9398)
			(end -0.508 0.9398)
			(stroke
				(width 0.1524)
				(type default)
			)
			(layer "F.SilkS")
		)
		(fp_line
			(start 0.508 -0.9398)
			(end -0.508 -0.9398)
			(stroke
				(width 0.1524)
				(type default)
			)
			(layer "F.SilkS")
		)
		(fp_rect
			(start -0.508 0.9398)
			(end 0.508 -0.9398)
			(stroke
				(width 0)
				(type default)
			)
			(fill no)
			(layer "F.CrtYd")
		)
		(fp_rect
			(start -0.508 0.9398)
			(end 0.508 -0.9398)
			(stroke
				(width 0)
				(type default)
			)
			(fill no)
			(layer "F.Fab")
		)
		(pad "1" smd custom
			(at 0 -0.4445)
			(size 0.1397 0.1397)
			(layers "F.Cu" "F.Mask" "F.Paste")
			(net "P3V3_PG")
			(options
				(clearance outline)
				(anchor circle)
			)
			(primitives
				(gr_poly
					(pts
						(arc
							(start -0.1778 -0.2794)
							(mid -0.249642 -0.249642)
							(end -0.2794 -0.1778)
						)
						(arc
							(start -0.2794 0.1778)
							(mid -0.249642 0.249642)
							(end -0.1778 0.2794)
						)
						(arc
							(start 0.1778 0.2794)
							(mid 0.249642 0.249642)
							(end 0.2794 0.1778)
						)
						(arc
							(start 0.2794 -0.1778)
							(mid 0.249642 -0.249642)
							(end 0.1778 -0.2794)
						)
					)
					(width 0)
					(fill yes)
				)
			)
		)
		(pad "2" smd custom
			(at 0 0.4445)
			(size 0.1397 0.1397)
			(layers "F.Cu" "F.Mask" "F.Paste")
			(net "TPS53312_P3V3_PG")
			(options
				(clearance outline)
				(anchor circle)
			)
			(primitives
				(gr_poly
					(pts
						(arc
							(start -0.1778 -0.2794)
							(mid -0.249642 -0.249642)
							(end -0.2794 -0.1778)
						)
						(arc
							(start -0.2794 0.1778)
							(mid -0.249642 0.249642)
							(end -0.1778 0.2794)
						)
						(arc
							(start 0.1778 0.2794)
							(mid 0.249642 0.249642)
							(end 0.2794 0.1778)
						)
						(arc
							(start 0.2794 -0.1778)
							(mid 0.249642 -0.249642)
							(end 0.1778 -0.2794)
						)
					)
					(width 0)
					(fill yes)
				)
			)
		)
	)
	(footprint ""
		(layer "F.Cu")
		(at 16.231362 -53.56733 180)
		(property "Reference" "R9955"
			(at 0 0 180)
			(layer "F.SilkS")
			(hide yes)
			(effects
				(font
					(size 1.27 1.27)
				)
			)
		)
		(property "Value" "4K7R2J-2-GP"
			(at 0.064008 -3.993896 180)
			(unlocked yes)
			(layer "F.Fab")
			(hide yes)
			(effects
				(font
					(size 1.016 1.016)
					(thickness 0.1524)
				)
			)
		)
		(property "Device Type" "R402H16"
			(at 0.064008 -5.517896 180)
			(unlocked yes)
			(layer "F.Fab")
			(hide yes)
			(effects
				(font
					(size 1.016 1.016)
					(thickness 0.1524)
				)
			)
		)
		(duplicate_pad_numbers_are_jumpers no)
		(fp_line
			(start 0.508 -0.9398)
			(end -0.508 -0.9398)
			(stroke
				(width 0.1524)
				(type default)
			)
			(layer "F.SilkS")
		)
		(fp_line
			(start -0.508 -0.9398)
			(end -0.508 0.9398)
			(stroke
				(width 0.1524)
				(type default)
			)
			(layer "F.SilkS")
		)
		(fp_rect
			(start -0.508 0.9398)
			(end 0.508 -0.9398)
			(stroke
				(width 0)
				(type default)
			)
			(fill no)
			(layer "F.CrtYd")
		)
		(fp_rect
			(start -0.508 0.9398)
			(end 0.508 -0.9398)
			(stroke
				(width 0)
				(type default)
			)
			(fill no)
			(layer "F.Fab")
		)
		(pad "1" smd custom
			(at 0 -0.4445 180)
			(size 0.1397 0.1397)
			(layers "F.Cu" "F.Mask" "F.Paste")
			(net "P3V3")
			(options
				(clearance outline)
				(anchor circle)
			)
			(primitives
				(gr_poly
					(pts
						(arc
							(start -0.1778 -0.2794)
							(mid -0.249642 -0.249642)
							(end -0.2794 -0.1778)
						)
						(arc
							(start -0.2794 0.1778)
							(mid -0.249642 0.249642)
							(end -0.1778 0.2794)
						)
						(arc
							(start 0.1778 0.2794)
							(mid 0.249642 0.249642)
							(end 0.2794 0.1778)
						)
						(arc
							(start 0.2794 -0.1778)
							(mid 0.249642 -0.249642)
							(end 0.1778 -0.2794)
						)
					)
					(width 0)
					(fill yes)
				)
			)
		)
		(pad "2" smd custom
			(at 0 0.4445 180)
			(size 0.1397 0.1397)
			(layers "F.Cu" "F.Mask" "F.Paste")
			(net "ATTN_LED_DR14_MOS_N")
			(options
				(clearance outline)
				(anchor circle)
			)
			(primitives
				(gr_poly
					(pts
						(arc
							(start -0.1778 -0.2794)
							(mid -0.249642 -0.249642)
							(end -0.2794 -0.1778)
						)
						(arc
							(start -0.2794 0.1778)
							(mid -0.249642 0.249642)
							(end -0.1778 0.2794)
						)
						(arc
							(start 0.1778 0.2794)
							(mid 0.249642 0.249642)
							(end 0.2794 0.1778)
						)
						(arc
							(start 0.2794 -0.1778)
							(mid 0.249642 -0.249642)
							(end 0.1778 -0.2794)
						)
					)
					(width 0)
					(fill yes)
				)
			)
		)
	)
	(footprint ""
		(layer "F.Cu")
		(at 220.726 -138.04011)
		(property "Reference" "Q44"
			(at 0 0 0)
			(layer "F.SilkS")
			(hide yes)
			(effects
				(font
					(size 1.27 1.27)
				)
			)
		)
		(property "Value" "2N7002A-7-GP"
			(at 0.127 -8.9662 0)
			(unlocked yes)
			(layer "F.Fab")
			(hide yes)
			(effects
				(font
					(size 1.016 1.016)
					(thickness 0.1524)
				)
			)
		)
		(property "Device Type" "SOT23DGS2D4H48"
			(at 0.127 -10.4902 0)
			(unlocked yes)
			(layer "F.Fab")
			(hide yes)
			(effects
				(font
					(size 1.016 1.016)
					(thickness 0.1524)
				)
			)
		)
		(duplicate_pad_numbers_are_jumpers no)
		(fp_line
			(start -1.651 -1.778)
			(end -1.651 1.778)
			(stroke
				(width 0.1524)
				(type default)
			)
			(layer "F.SilkS")
		)
		(fp_line
			(start -1.651 1.778)
			(end 1.651 1.778)
			(stroke
				(width 0.1524)
				(type default)
			)
			(layer "F.SilkS")
		)
		(fp_line
			(start 1.651 -1.778)
			(end -1.651 -1.778)
			(stroke
				(width 0.1524)
				(type default)
			)
			(layer "F.SilkS")
		)
		(fp_line
			(start 1.651 1.778)
			(end 1.651 -1.778)
			(stroke
				(width 0.1524)
				(type default)
			)
			(layer "F.SilkS")
		)
		(fp_poly
			(pts
				(xy -1.778 1.8796) (xy -1.778 -1.8796) (xy 1.778 -1.8796) (xy 1.778 1.8796)
			)
			(stroke
				(width 0)
				(type default)
			)
			(fill no)
			(layer "F.CrtYd")
		)
		(fp_poly
			(pts
				(xy -1.778 1.8796) (xy -1.778 -1.8796) (xy 1.778 -1.8796) (xy 1.778 1.8796)
			)
			(stroke
				(width 0)
				(type default)
			)
			(fill no)
			(layer "F.Fab")
		)
		(pad "D" smd custom
			(at 0 -0.9525)
			(size 0.1905 0.1905)
			(layers "F.Cu" "F.Mask" "F.Paste")
			(net "SSD3_CLK0_OE_MOS_N")
			(options
				(clearance outline)
				(anchor circle)
			)
			(primitives
				(gr_poly
					(pts
						(arc
							(start -0.1778 0.5715)
							(mid -0.321484 0.511984)
							(end -0.381 0.3683)
						)
						(arc
							(start -0.381 -0.3683)
							(mid -0.321484 -0.511984)
							(end -0.1778 -0.5715)
						)
						(arc
							(start 0.1778 -0.5715)
							(mid 0.321484 -0.511984)
							(end 0.381 -0.3683)
						)
						(arc
							(start 0.381 0.3683)
							(mid 0.321484 0.511984)
							(end 0.1778 0.5715)
						)
					)
					(width 0)
					(fill yes)
				)
			)
		)
		(pad "G" smd custom
			(at -0.98425 0.9525)
			(size 0.1905 0.1905)
			(layers "F.Cu" "F.Mask" "F.Paste")
			(net "SSD3_CLK0_OE_R_N")
			(options
				(clearance outline)
				(anchor circle)
			)
			(primitives
				(gr_poly
					(pts
						(arc
							(start -0.1778 0.5715)
							(mid -0.321484 0.511984)
							(end -0.381 0.3683)
						)
						(arc
							(start -0.381 -0.3683)
							(mid -0.321484 -0.511984)
							(end -0.1778 -0.5715)
						)
						(arc
							(start 0.1778 -0.5715)
							(mid 0.321484 -0.511984)
							(end 0.381 -0.3683)
						)
						(arc
							(start 0.381 0.3683)
							(mid 0.321484 0.511984)
							(end 0.1778 0.5715)
						)
					)
					(width 0)
					(fill yes)
				)
			)
		)
		(pad "S" smd custom
			(at 0.98425 0.9525)
			(size 0.1905 0.1905)
			(layers "F.Cu" "F.Mask" "F.Paste")
			(net "GND")
			(options
				(clearance outline)
				(anchor circle)
			)
			(primitives
				(gr_poly
					(pts
						(arc
							(start -0.1778 0.5715)
							(mid -0.321484 0.511984)
							(end -0.381 0.3683)
						)
						(arc
							(start -0.381 -0.3683)
							(mid -0.321484 -0.511984)
							(end -0.1778 -0.5715)
						)
						(arc
							(start 0.1778 -0.5715)
							(mid 0.321484 -0.511984)
							(end 0.381 -0.3683)
						)
						(arc
							(start 0.381 0.3683)
							(mid 0.321484 0.511984)
							(end 0.1778 0.5715)
						)
					)
					(width 0)
					(fill yes)
				)
			)
		)
	)
)
